(kicad_pcb
	(version 20260206)
	(generator "pcbnew")
	(generator_version "10.0")
	(general
		(thickness 1.6)
		(legacy_teardrops no)
	)
	(paper "A4")
	(title_block
		(title "04192023_DAF0TMB3IC0_F0TG_MB_C_brd_V02_OCP.brd")
		(comment 1 "Grand Teton / footprints 6140-6145 of 8354")
	)
	(layers
		(0 "F.Cu" signal "TOP")
		(4 "In1.Cu" signal "GND")
		(6 "In2.Cu" signal "IN1")
		(8 "In3.Cu" signal "GND1")
		(10 "In4.Cu" signal "IN2")
		(12 "In5.Cu" signal "GND2")
		(14 "In6.Cu" signal "IN3")
		(16 "In7.Cu" signal "GND3")
		(18 "In8.Cu" signal "VCC")
		(20 "In9.Cu" signal "VCC1")
		(22 "In10.Cu" signal "GND4")
		(24 "In11.Cu" signal "IN4")
		(26 "In12.Cu" signal "GND5")
		(28 "In13.Cu" signal "IN5")
		(30 "In14.Cu" signal "GND6")
		(32 "In15.Cu" signal "IN6")
		(34 "In16.Cu" signal "GND7")
		(2 "B.Cu" signal "BOTTOM")
		(9 "F.Adhes" user "F.Adhesive")
		(11 "B.Adhes" user "B.Adhesive")
		(13 "F.Paste" user "Package Geometry/Pastemask Top")
		(15 "B.Paste" user "Package Geometry/Pastemask Bottom")
		(5 "F.SilkS" user "Ref Des/Silkscreen Top")
		(7 "B.SilkS" user "Ref Des/Silkscreen Bottom")
		(1 "F.Mask" user "Board Geometry/Soldermask Top")
		(3 "B.Mask" user "Board Geometry/Soldermask Bottom")
		(17 "Dwgs.User" user "User.Drawings")
		(19 "Cmts.User" user "User.Comments")
		(21 "Eco1.User" user "User.Eco1")
		(23 "Eco2.User" user "User.Eco2")
		(25 "Edge.Cuts" user "Board Geometry/Outline")
		(27 "Margin" user)
		(31 "F.CrtYd" user "Package Geometry/Place Bound Top")
		(29 "B.CrtYd" user "Package Geometry/Place Bound Bottom")
		(35 "F.Fab" user "Ref Des/Assembly Top")
		(33 "B.Fab" user "Ref Des/Assembly Bottom")
	)
	(footprint ""
		(layer "B.Cu")
		(at 270.247872 -338.127086 -90)
		(property "Reference" "PR410"
			(at 0 0 90)
			(layer "B.SilkS")
			(hide yes)
			(effects
				(font
					(size 1.27 1.27)
				)
				(justify mirror)
			)
		)
		(property "Value" ""
			(at 0 0 90)
			(layer "B.Fab")
			(effects
				(font
					(size 1.27 1.27)
				)
				(justify mirror)
			)
		)
		(duplicate_pad_numbers_are_jumpers no)
		(fp_line
			(start -0.7874 0.4064)
			(end 0.7874 0.4064)
			(stroke
				(width 0.1524)
				(type default)
			)
			(layer "B.SilkS")
		)
		(fp_line
			(start 0.7874 0.4064)
			(end 0.7874 -0.4064)
			(stroke
				(width 0.1524)
				(type default)
			)
			(layer "B.SilkS")
		)
		(fp_line
			(start -0.7874 -0.4064)
			(end -0.7874 0.4064)
			(stroke
				(width 0.1524)
				(type default)
			)
			(layer "B.SilkS")
		)
		(fp_line
			(start 0.7874 -0.4064)
			(end -0.7874 -0.4064)
			(stroke
				(width 0.1524)
				(type default)
			)
			(layer "B.SilkS")
		)
		(fp_line
			(start -0.67945 0.3048)
			(end -0.120396 0.3048)
			(stroke
				(width 0.1)
				(type default)
			)
			(layer "B.Fab")
		)
		(fp_line
			(start -0.120396 0.3048)
			(end -0.120396 0.2794)
			(stroke
				(width 0.1)
				(type default)
			)
			(layer "B.Fab")
		)
		(fp_line
			(start 0.12065 0.3048)
			(end 0.67945 0.3048)
			(stroke
				(width 0.1)
				(type default)
			)
			(layer "B.Fab")
		)
		(fp_line
			(start 0.67945 0.3048)
			(end 0.67945 -0.305054)
			(stroke
				(width 0.1)
				(type default)
			)
			(layer "B.Fab")
		)
		(fp_line
			(start -0.120396 0.2794)
			(end 0.12065 0.2794)
			(stroke
				(width 0.1)
				(type default)
			)
			(layer "B.Fab")
		)
		(fp_line
			(start 0.12065 0.2794)
			(end 0.12065 0.3048)
			(stroke
				(width 0.1)
				(type default)
			)
			(layer "B.Fab")
		)
		(fp_line
			(start -0.12065 -0.2794)
			(end -0.12065 -0.3048)
			(stroke
				(width 0.1)
				(type default)
			)
			(layer "B.Fab")
		)
		(fp_line
			(start 0.12065 -0.2794)
			(end -0.12065 -0.2794)
			(stroke
				(width 0.1)
				(type default)
			)
			(layer "B.Fab")
		)
		(fp_line
			(start -0.67945 -0.3048)
			(end -0.67945 0.3048)
			(stroke
				(width 0.1)
				(type default)
			)
			(layer "B.Fab")
		)
		(fp_line
			(start -0.12065 -0.3048)
			(end -0.67945 -0.3048)
			(stroke
				(width 0.1)
				(type default)
			)
			(layer "B.Fab")
		)
		(fp_line
			(start 0.12065 -0.305054)
			(end 0.12065 -0.2794)
			(stroke
				(width 0.1)
				(type default)
			)
			(layer "B.Fab")
		)
		(fp_line
			(start 0.67945 -0.305054)
			(end 0.12065 -0.305054)
			(stroke
				(width 0.1)
				(type default)
			)
			(layer "B.Fab")
		)
		(pad "1" smd circle
			(at 0.40005 0 90)
			(size 0 0)
			(layers "B.Cu" "B.Mask" "B.Paste")
			(net "PVDDIO_P0")
		)
		(pad "2" smd circle
			(at -0.40005 0 90)
			(size 0 0)
			(layers "B.Cu" "B.Mask" "B.Paste")
			(net "GND")
		)
	)
	(footprint ""
		(layer "B.Cu")
		(at 105.960164 -258.405376 180)
		(property "Reference" "C2479"
			(at 0 0 0)
			(layer "B.SilkS")
			(hide yes)
			(effects
				(font
					(size 1.27 1.27)
				)
				(justify mirror)
			)
		)
		(property "Value" ""
			(at 0 0 0)
			(layer "B.Fab")
			(effects
				(font
					(size 1.27 1.27)
				)
				(justify mirror)
			)
		)
		(duplicate_pad_numbers_are_jumpers no)
		(fp_line
			(start 0.7874 0.4064)
			(end 0.7874 -0.4064)
			(stroke
				(width 0.1524)
				(type default)
			)
			(layer "B.SilkS")
		)
		(fp_line
			(start 0.7874 -0.4064)
			(end -0.7874 -0.4064)
			(stroke
				(width 0.1524)
				(type default)
			)
			(layer "B.SilkS")
		)
		(fp_line
			(start -0.7874 0.4064)
			(end 0.7874 0.4064)
			(stroke
				(width 0.1524)
				(type default)
			)
			(layer "B.SilkS")
		)
		(fp_line
			(start -0.7874 -0.4064)
			(end -0.7874 0.4064)
			(stroke
				(width 0.1524)
				(type default)
			)
			(layer "B.SilkS")
		)
		(fp_line
			(start 0.67945 0.3048)
			(end 0.67945 -0.305054)
			(stroke
				(width 0.1)
				(type default)
			)
			(layer "B.Fab")
		)
		(fp_line
			(start 0.67945 -0.305054)
			(end 0.12065 -0.305054)
			(stroke
				(width 0.1)
				(type default)
			)
			(layer "B.Fab")
		)
		(fp_line
			(start 0.12065 0.3048)
			(end 0.67945 0.3048)
			(stroke
				(width 0.1)
				(type default)
			)
			(layer "B.Fab")
		)
		(fp_line
			(start 0.12065 0.2794)
			(end 0.12065 0.3048)
			(stroke
				(width 0.1)
				(type default)
			)
			(layer "B.Fab")
		)
		(fp_line
			(start 0.12065 -0.2794)
			(end -0.12065 -0.2794)
			(stroke
				(width 0.1)
				(type default)
			)
			(layer "B.Fab")
		)
		(fp_line
			(start 0.12065 -0.305054)
			(end 0.12065 -0.2794)
			(stroke
				(width 0.1)
				(type default)
			)
			(layer "B.Fab")
		)
		(fp_line
			(start -0.120396 0.3048)
			(end -0.120396 0.2794)
			(stroke
				(width 0.1)
				(type default)
			)
			(layer "B.Fab")
		)
		(fp_line
			(start -0.120396 0.2794)
			(end 0.12065 0.2794)
			(stroke
				(width 0.1)
				(type default)
			)
			(layer "B.Fab")
		)
		(fp_line
			(start -0.12065 -0.2794)
			(end -0.12065 -0.3048)
			(stroke
				(width 0.1)
				(type default)
			)
			(layer "B.Fab")
		)
		(fp_line
			(start -0.12065 -0.3048)
			(end -0.67945 -0.3048)
			(stroke
				(width 0.1)
				(type default)
			)
			(layer "B.Fab")
		)
		(fp_line
			(start -0.67945 0.3048)
			(end -0.120396 0.3048)
			(stroke
				(width 0.1)
				(type default)
			)
			(layer "B.Fab")
		)
		(fp_line
			(start -0.67945 -0.3048)
			(end -0.67945 0.3048)
			(stroke
				(width 0.1)
				(type default)
			)
			(layer "B.Fab")
		)
		(pad "1" smd circle
			(at 0.40005 0)
			(size 0 0)
			(layers "B.Cu" "B.Mask" "B.Paste")
			(net "PVDDIO_P1")
		)
		(pad "2" smd circle
			(at -0.40005 0)
			(size 0 0)
			(layers "B.Cu" "B.Mask" "B.Paste")
			(net "GND")
		)
	)
	(footprint ""
		(layer "B.Cu")
		(at 144.932654 -315.49467 180)
		(property "Reference" "R547"
			(at 0 0 0)
			(layer "B.SilkS")
			(hide yes)
			(effects
				(font
					(size 1.27 1.27)
				)
				(justify mirror)
			)
		)
		(property "Value" ""
			(at 0 0 0)
			(layer "B.Fab")
			(effects
				(font
					(size 1.27 1.27)
				)
				(justify mirror)
			)
		)
		(duplicate_pad_numbers_are_jumpers no)
		(fp_line
			(start 0.7874 0.4064)
			(end 0.7874 -0.4064)
			(stroke
				(width 0.1524)
				(type default)
			)
			(layer "B.SilkS")
		)
		(fp_line
			(start 0.7874 -0.4064)
			(end -0.7874 -0.4064)
			(stroke
				(width 0.1524)
				(type default)
			)
			(layer "B.SilkS")
		)
		(fp_line
			(start -0.7874 0.4064)
			(end 0.7874 0.4064)
			(stroke
				(width 0.1524)
				(type default)
			)
			(layer "B.SilkS")
		)
		(fp_line
			(start -0.7874 -0.4064)
			(end -0.7874 0.4064)
			(stroke
				(width 0.1524)
				(type default)
			)
			(layer "B.SilkS")
		)
		(fp_line
			(start 0.67945 0.3048)
			(end 0.67945 -0.305054)
			(stroke
				(width 0.1)
				(type default)
			)
			(layer "B.Fab")
		)
		(fp_line
			(start 0.67945 -0.305054)
			(end 0.12065 -0.305054)
			(stroke
				(width 0.1)
				(type default)
			)
			(layer "B.Fab")
		)
		(fp_line
			(start 0.12065 0.3048)
			(end 0.67945 0.3048)
			(stroke
				(width 0.1)
				(type default)
			)
			(layer "B.Fab")
		)
		(fp_line
			(start 0.12065 0.2794)
			(end 0.12065 0.3048)
			(stroke
				(width 0.1)
				(type default)
			)
			(layer "B.Fab")
		)
		(fp_line
			(start 0.12065 -0.2794)
			(end -0.12065 -0.2794)
			(stroke
				(width 0.1)
				(type default)
			)
			(layer "B.Fab")
		)
		(fp_line
			(start 0.12065 -0.305054)
			(end 0.12065 -0.2794)
			(stroke
				(width 0.1)
				(type default)
			)
			(layer "B.Fab")
		)
		(fp_line
			(start -0.120396 0.3048)
			(end -0.120396 0.2794)
			(stroke
				(width 0.1)
				(type default)
			)
			(layer "B.Fab")
		)
		(fp_line
			(start -0.120396 0.2794)
			(end 0.12065 0.2794)
			(stroke
				(width 0.1)
				(type default)
			)
			(layer "B.Fab")
		)
		(fp_line
			(start -0.12065 -0.2794)
			(end -0.12065 -0.3048)
			(stroke
				(width 0.1)
				(type default)
			)
			(layer "B.Fab")
		)
		(fp_line
			(start -0.12065 -0.3048)
			(end -0.67945 -0.3048)
			(stroke
				(width 0.1)
				(type default)
			)
			(layer "B.Fab")
		)
		(fp_line
			(start -0.67945 0.3048)
			(end -0.120396 0.3048)
			(stroke
				(width 0.1)
				(type default)
			)
			(layer "B.Fab")
		)
		(fp_line
			(start -0.67945 -0.3048)
			(end -0.67945 0.3048)
			(stroke
				(width 0.1)
				(type default)
			)
			(layer "B.Fab")
		)
		(pad "1" smd circle
			(at 0.40005 0)
			(size 0 0)
			(layers "B.Cu" "B.Mask" "B.Paste")
			(net "FM_CPU1_BMC_RST_N")
		)
		(pad "2" smd circle
			(at -0.40005 0)
			(size 0 0)
			(layers "B.Cu" "B.Mask" "B.Paste")
			(net "PVDD18_S5_P1")
		)
	)
	(footprint ""
		(layer "B.Cu")
		(at 121.706386 -250.892564)
		(property "Reference" "C2449"
			(at 0 0 0)
			(layer "B.SilkS")
			(hide yes)
			(effects
				(font
					(size 1.27 1.27)
				)
				(justify mirror)
			)
		)
		(property "Value" ""
			(at 0 0 0)
			(layer "B.Fab")
			(effects
				(font
					(size 1.27 1.27)
				)
				(justify mirror)
			)
		)
		(duplicate_pad_numbers_are_jumpers no)
		(fp_line
			(start -0.7874 -0.4064)
			(end -0.7874 0.4064)
			(stroke
				(width 0.1524)
				(type default)
			)
			(layer "B.SilkS")
		)
		(fp_line
			(start -0.7874 0.4064)
			(end 0.7874 0.4064)
			(stroke
				(width 0.1524)
				(type default)
			)
			(layer "B.SilkS")
		)
		(fp_line
			(start 0.7874 -0.4064)
			(end -0.7874 -0.4064)
			(stroke
				(width 0.1524)
				(type default)
			)
			(layer "B.SilkS")
		)
		(fp_line
			(start 0.7874 0.4064)
			(end 0.7874 -0.4064)
			(stroke
				(width 0.1524)
				(type default)
			)
			(layer "B.SilkS")
		)
		(fp_line
			(start -0.67945 -0.3048)
			(end -0.67945 0.3048)
			(stroke
				(width 0.1)
				(type default)
			)
			(layer "B.Fab")
		)
		(fp_line
			(start -0.67945 0.3048)
			(end -0.120396 0.3048)
			(stroke
				(width 0.1)
				(type default)
			)
			(layer "B.Fab")
		)
		(fp_line
			(start -0.12065 -0.3048)
			(end -0.67945 -0.3048)
			(stroke
				(width 0.1)
				(type default)
			)
			(layer "B.Fab")
		)
		(fp_line
			(start -0.12065 -0.2794)
			(end -0.12065 -0.3048)
			(stroke
				(width 0.1)
				(type default)
			)
			(layer "B.Fab")
		)
		(fp_line
			(start -0.120396 0.2794)
			(end 0.12065 0.2794)
			(stroke
				(width 0.1)
				(type default)
			)
			(layer "B.Fab")
		)
		(fp_line
			(start -0.120396 0.3048)
			(end -0.120396 0.2794)
			(stroke
				(width 0.1)
				(type default)
			)
			(layer "B.Fab")
		)
		(fp_line
			(start 0.12065 -0.305054)
			(end 0.12065 -0.2794)
			(stroke
				(width 0.1)
				(type default)
			)
			(layer "B.Fab")
		)
		(fp_line
			(start 0.12065 -0.2794)
			(end -0.12065 -0.2794)
			(stroke
				(width 0.1)
				(type default)
			)
			(layer "B.Fab")
		)
		(fp_line
			(start 0.12065 0.2794)
			(end 0.12065 0.3048)
			(stroke
				(width 0.1)
				(type default)
			)
			(layer "B.Fab")
		)
		(fp_line
			(start 0.12065 0.3048)
			(end 0.67945 0.3048)
			(stroke
				(width 0.1)
				(type default)
			)
			(layer "B.Fab")
		)
		(fp_line
			(start 0.67945 -0.305054)
			(end 0.12065 -0.305054)
			(stroke
				(width 0.1)
				(type default)
			)
			(layer "B.Fab")
		)
		(fp_line
			(start 0.67945 0.3048)
			(end 0.67945 -0.305054)
			(stroke
				(width 0.1)
				(type default)
			)
			(layer "B.Fab")
		)
		(pad "1" smd circle
			(at 0.40005 0 180)
			(size 0 0)
			(layers "B.Cu" "B.Mask" "B.Paste")
			(net "PVDDCR_SOC_P1")
		)
		(pad "2" smd circle
			(at -0.40005 0 180)
			(size 0 0)
			(layers "B.Cu" "B.Mask" "B.Paste")
			(net "GND")
		)
	)
	(footprint ""
		(layer "B.Cu")
		(at 228.479604 -327.56602 180)
		(property "Reference" "C1089"
			(at 0 0 0)
			(layer "B.SilkS")
			(hide yes)
			(effects
				(font
					(size 1.27 1.27)
				)
				(justify mirror)
			)
		)
		(property "Value" ""
			(at 0 0 0)
			(layer "B.Fab")
			(effects
				(font
					(size 1.27 1.27)
				)
				(justify mirror)
			)
		)
		(duplicate_pad_numbers_are_jumpers no)
		(fp_line
			(start 0.7874 0.4064)
			(end 0.7874 -0.4064)
			(stroke
				(width 0.1524)
				(type default)
			)
			(layer "B.SilkS")
		)
		(fp_line
			(start 0.7874 -0.4064)
			(end -0.7874 -0.4064)
			(stroke
				(width 0.1524)
				(type default)
			)
			(layer "B.SilkS")
		)
		(fp_line
			(start -0.7874 0.4064)
			(end 0.7874 0.4064)
			(stroke
				(width 0.1524)
				(type default)
			)
			(layer "B.SilkS")
		)
		(fp_line
			(start -0.7874 -0.4064)
			(end -0.7874 0.4064)
			(stroke
				(width 0.1524)
				(type default)
			)
			(layer "B.SilkS")
		)
		(fp_line
			(start 0.67945 0.3048)
			(end 0.67945 -0.305054)
			(stroke
				(width 0.1)
				(type default)
			)
			(layer "B.Fab")
		)
		(fp_line
			(start 0.67945 -0.305054)
			(end 0.12065 -0.305054)
			(stroke
				(width 0.1)
				(type default)
			)
			(layer "B.Fab")
		)
		(fp_line
			(start 0.12065 0.3048)
			(end 0.67945 0.3048)
			(stroke
				(width 0.1)
				(type default)
			)
			(layer "B.Fab")
		)
		(fp_line
			(start 0.12065 0.2794)
			(end 0.12065 0.3048)
			(stroke
				(width 0.1)
				(type default)
			)
			(layer "B.Fab")
		)
		(fp_line
			(start 0.12065 -0.2794)
			(end -0.12065 -0.2794)
			(stroke
				(width 0.1)
				(type default)
			)
			(layer "B.Fab")
		)
		(fp_line
			(start 0.12065 -0.305054)
			(end 0.12065 -0.2794)
			(stroke
				(width 0.1)
				(type default)
			)
			(layer "B.Fab")
		)
		(fp_line
			(start -0.120396 0.3048)
			(end -0.120396 0.2794)
			(stroke
				(width 0.1)
				(type default)
			)
			(layer "B.Fab")
		)
		(fp_line
			(start -0.120396 0.2794)
			(end 0.12065 0.2794)
			(stroke
				(width 0.1)
				(type default)
			)
			(layer "B.Fab")
		)
		(fp_line
			(start -0.12065 -0.2794)
			(end -0.12065 -0.3048)
			(stroke
				(width 0.1)
				(type default)
			)
			(layer "B.Fab")
		)
		(fp_line
			(start -0.12065 -0.3048)
			(end -0.67945 -0.3048)
			(stroke
				(width 0.1)
				(type default)
			)
			(layer "B.Fab")
		)
		(fp_line
			(start -0.67945 0.3048)
			(end -0.120396 0.3048)
			(stroke
				(width 0.1)
				(type default)
			)
			(layer "B.Fab")
		)
		(fp_line
			(start -0.67945 -0.3048)
			(end -0.67945 0.3048)
			(stroke
				(width 0.1)
				(type default)
			)
			(layer "B.Fab")
		)
		(pad "1" smd circle
			(at 0.40005 0)
			(size 0 0)
			(layers "B.Cu" "B.Mask" "B.Paste")
			(net "PVDD_33_S5_ADC_TIC")
		)
		(pad "2" smd circle
			(at -0.40005 0)
			(size 0 0)
			(layers "B.Cu" "B.Mask" "B.Paste")
			(net "GND")
		)
	)
	(footprint ""
		(layer "B.Cu")
		(at 109.22 -415.036 -90)
		(property "Reference" "Q148"
			(at 4.3942 0.12827 270)
			(unlocked yes)
			(layer "B.SilkS")
			(effects
				(font
					(size 0.7874 0.5842)
					(thickness 0.1524)
				)
				(justify left mirror)
			)
		)
		(property "Value" ""
			(at 0 0 90)
			(layer "B.Fab")
			(effects
				(font
					(size 1.27 1.27)
				)
				(justify mirror)
			)
		)
		(duplicate_pad_numbers_are_jumpers no)
		(fp_line
			(start -1.332738 1.100074)
			(end 1.332738 1.100074)
			(stroke
				(width 0.1524)
				(type default)
			)
			(layer "B.SilkS")
		)
		(fp_line
			(start 1.332738 1.100074)
			(end 1.332738 -1.100074)
			(stroke
				(width 0.1524)
				(type default)
			)
			(layer "B.SilkS")
		)
		(fp_line
			(start 0 -0.541274)
			(end -0.4826 -1.100074)
			(stroke
				(width 0.1524)
				(type default)
			)
			(layer "B.SilkS")
		)
		(fp_line
			(start -1.332738 -1.100074)
			(end -1.332738 1.100074)
			(stroke
				(width 0.1524)
				(type default)
			)
			(layer "B.SilkS")
		)
		(fp_line
			(start -0.4826 -1.100074)
			(end -1.332738 -1.100074)
			(stroke
				(width 0.1524)
				(type default)
			)
			(layer "B.SilkS")
		)
		(fp_line
			(start 0.4826 -1.100074)
			(end 0 -0.541274)
			(stroke
				(width 0.1524)
				(type default)
			)
			(layer "B.SilkS")
		)
		(fp_line
			(start 1.332738 -1.100074)
			(end 0.4826 -1.100074)
			(stroke
				(width 0.1524)
				(type default)
			)
			(layer "B.SilkS")
		)
		(fp_poly
			(pts
				(xy 0.513334 -1.311148) (xy 0.295402 -2.065274) (xy -0.220726 -1.589278)
			)
			(stroke
				(width 0)
				(type default)
			)
			(fill yes)
			(layer "B.SilkS")
		)
		(fp_line
			(start -0.674878 1.100074)
			(end 0.674878 1.100074)
			(stroke
				(width 0.1)
				(type default)
			)
			(layer "B.Fab")
		)
		(fp_line
			(start 0.674878 1.100074)
			(end 0.674878 -1.100074)
			(stroke
				(width 0.1)
				(type default)
			)
			(layer "B.Fab")
		)
		(fp_line
			(start -0.674878 -1.100074)
			(end -0.674878 1.100074)
			(stroke
				(width 0.1)
				(type default)
			)
			(layer "B.Fab")
		)
		(fp_line
			(start 0.674878 -1.100074)
			(end -0.674878 -1.100074)
			(stroke
				(width 0.1)
				(type default)
			)
			(layer "B.Fab")
		)
		(fp_poly
			(pts
				(xy 2.2352 -0.298958) (xy 2.2352 -1.001014) (xy 1.533144 -0.649986)
			)
			(stroke
				(width 0)
				(type default)
			)
			(fill yes)
			(layer "B.Fab")
		)
		(pad "1" smd rect
			(at 0.94996 -0.649986)
			(size 0.4318 0.508)
			(layers "B.Cu" "B.Mask" "B.Paste")
			(net "GND")
		)
		(pad "2" smd rect
			(at 0.94996 0)
			(size 0.4318 0.508)
			(layers "B.Cu" "B.Mask" "B.Paste")
			(net "HGX_DETECT_N")
		)
		(pad "3" smd rect
			(at 0.94996 0.649986)
			(size 0.4318 0.508)
			(layers "B.Cu" "B.Mask" "B.Paste")
			(net "HGX_DETECT_N_ISO")
		)
		(pad "4" smd rect
			(at -0.94996 0.649986)
			(size 0.4318 0.508)
			(layers "B.Cu" "B.Mask" "B.Paste")
			(net "GND")
		)
		(pad "5" smd rect
			(at -0.94996 0)
			(size 0.4318 0.508)
			(layers "B.Cu" "B.Mask" "B.Paste")
			(net "HGX_DETECT")
		)
		(pad "6" smd rect
			(at -0.94996 -0.649986)
			(size 0.4318 0.508)
			(layers "B.Cu" "B.Mask" "B.Paste")
			(net "HGX_DETECT")
		)
	)
)
